(kicad_pcb
	(version 20241229)
	(generator "pcbnew")
	(generator_version "9.0")
	(general
		(thickness 1.61)
		(legacy_teardrops no)
	)
	(paper "A3")
	(title_block
		(title "RDIMM DDR5 Tester")
		(date "2026-05-21")
		(rev "2.2.0")
		(company "Antmicro")
		(comment 9 "footprints 376-377 of 796")
	)
	(layers
		(0 "F.Cu" signal)
		(4 "In1.Cu" power)
		(6 "In2.Cu" mixed)
		(8 "In3.Cu" power)
		(10 "In4.Cu" mixed)
		(12 "In5.Cu" power)
		(14 "In6.Cu" mixed)
		(16 "In7.Cu" power)
		(18 "In8.Cu" power)
		(20 "In9.Cu" mixed)
		(22 "In10.Cu" power)
		(2 "B.Cu" signal)
		(9 "F.Adhes" user "F.Adhesive")
		(11 "B.Adhes" user "B.Adhesive")
		(13 "F.Paste" user)
		(15 "B.Paste" user)
		(5 "F.SilkS" user "F.Silkscreen")
		(7 "B.SilkS" user "B.Silkscreen")
		(1 "F.Mask" user)
		(3 "B.Mask" user)
		(17 "Dwgs.User" user "User.Drawings")
		(19 "Cmts.User" user "User.Comments")
		(21 "Eco1.User" user "User.Eco1")
		(23 "Eco2.User" user "User.Eco2")
		(25 "Edge.Cuts" user)
		(27 "Margin" user)
		(31 "F.CrtYd" user "F.Courtyard")
		(29 "B.CrtYd" user "B.Courtyard")
		(35 "F.Fab" user)
		(33 "B.Fab" user)
	)
	(footprint "antmicro-footprints:PinHeader_2x7_P2mm_SMD_Shrouded_no-locator"
		(layer "F.Cu")
		(at 225.472 146.85 90)
		(descr "Pin Header 2x7 SMD Shrouded no-locator")
		(property "Reference" "J1"
			(at -9.85 3.753 0)
			(layer "F.SilkS")
			(effects
				(font
					(size 0.7 0.7)
					(thickness 0.15)
				)
				(justify right bottom)
			)
		)
		(property "Value" "PinHeader_2x7_P2mm_SMD_Shrouded_no-locator"
			(at 0 5.038 90)
			(layer "F.Fab")
			(effects
				(font
					(size 0.7 0.7)
					(thickness 0.15)
				)
				(justify left bottom)
			)
		)
		(property "Datasheet" "https://www.molex.com/pdm_docs/ps/PS-87831-027-001.pdf"
			(at 0 0 90)
			(layer "F.Fab")
			(hide yes)
			(effects
				(font
					(size 1.27 1.27)
					(thickness 0.15)
				)
			)
		)
		(property "MPN" "878321412"
			(at 0 0 90)
			(unlocked yes)
			(layer "F.Fab")
			(hide yes)
			(effects
				(font
					(size 1 1)
					(thickness 0.15)
				)
			)
		)
		(property "Manufacturer" "Molex"
			(at 0 0 90)
			(unlocked yes)
			(layer "F.Fab")
			(hide yes)
			(effects
				(font
					(size 1 1)
					(thickness 0.15)
				)
			)
		)
		(property "Author" "Antmicro"
			(at 0 0 90)
			(unlocked yes)
			(layer "F.Fab")
			(hide yes)
			(effects
				(font
					(size 1 1)
					(thickness 0.15)
				)
			)
		)
		(property "License" "Apache-2.0"
			(at 0 0 90)
			(unlocked yes)
			(layer "F.Fab")
			(hide yes)
			(effects
				(font
					(size 1 1)
					(thickness 0.15)
				)
			)
		)
		(sheetname "/FPGA Config/")
		(sheetfile "fpga-config.kicad_sch")
		(attr smd exclude_from_bom dnp)
		(fp_line
			(start 8.499 -3.301)
			(end 7.998 -3.301)
			(stroke
				(width 0.15)
				(type solid)
			)
			(layer "F.SilkS")
		)
		(fp_line
			(start 8.499 -3.301)
			(end 8.499 -2.801)
			(stroke
				(width 0.15)
				(type solid)
			)
			(layer "F.SilkS")
		)
		(fp_line
			(start -8.5 -3.301)
			(end -8 -3.301)
			(stroke
				(width 0.15)
				(type solid)
			)
			(layer "F.SilkS")
		)
		(fp_line
			(start -8.5 -3.301)
			(end -8.5 -2.801)
			(stroke
				(width 0.15)
				(type solid)
			)
			(layer "F.SilkS")
		)
		(fp_line
			(start -1.397 2.41)
			(end -0.9 2.41)
			(stroke
				(width 0.15)
				(type solid)
			)
			(layer "F.SilkS")
		)
		(fp_line
			(start -1.397 2.41)
			(end -1.397 2.91)
			(stroke
				(width 0.15)
				(type solid)
			)
			(layer "F.SilkS")
		)
		(fp_line
			(start 1.394 2.418)
			(end 0.897 2.418)
			(stroke
				(width 0.15)
				(type solid)
			)
			(layer "F.SilkS")
		)
		(fp_line
			(start 1.394 2.418)
			(end 1.394 2.918)
			(stroke
				(width 0.15)
				(type solid)
			)
			(layer "F.SilkS")
		)
		(fp_line
			(start 8.499 3.297)
			(end 8.499 2.797)
			(stroke
				(width 0.15)
				(type solid)
			)
			(layer "F.SilkS")
		)
		(fp_line
			(start 8.499 3.297)
			(end 7.998 3.297)
			(stroke
				(width 0.15)
				(type solid)
			)
			(layer "F.SilkS")
		)
		(fp_line
			(start -8.5 3.297)
			(end -8.5 2.797)
			(stroke
				(width 0.15)
				(type solid)
			)
			(layer "F.SilkS")
		)
		(fp_line
			(start -8.5 3.297)
			(end -8 3.297)
			(stroke
				(width 0.15)
				(type solid)
			)
			(layer "F.SilkS")
		)
		(fp_circle
			(center -6.8 3.4)
			(end -6.748 3.4)
			(stroke
				(width 0.15)
				(type solid)
			)
			(fill yes)
			(layer "F.SilkS")
		)
		(fp_rect
			(start -8.7 -3.7)
			(end 8.7 3.7)
			(stroke
				(width 0.05)
				(type solid)
			)
			(fill no)
			(layer "F.CrtYd")
		)
		(fp_line
			(start -8.325 -3.15)
			(end 8.323 -3.15)
			(stroke
				(width 0.15)
				(type solid)
			)
			(layer "F.Fab")
		)
		(fp_line
			(start 1.394 2.41)
			(end 1.394 3.14)
			(stroke
				(width 0.15)
				(type solid)
			)
			(layer "F.Fab")
		)
		(fp_line
			(start -1.397 2.41)
			(end 1.394 2.41)
			(stroke
				(width 0.15)
				(type solid)
			)
			(layer "F.Fab")
		)
		(fp_line
			(start -1.397 2.41)
			(end -1.397 3.14)
			(stroke
				(width 0.15)
				(type solid)
			)
			(layer "F.Fab")
		)
		(fp_line
			(start 8.323 3.148)
			(end 8.323 -3.15)
			(stroke
				(width 0.15)
				(type solid)
			)
			(layer "F.Fab")
		)
		(fp_line
			(start 1.394 3.148)
			(end 8.323 3.148)
			(stroke
				(width 0.15)
				(type solid)
			)
			(layer "F.Fab")
		)
		(fp_line
			(start -8.325 3.148)
			(end -8.325 -3.15)
			(stroke
				(width 0.15)
				(type solid)
			)
			(layer "F.Fab")
		)
		(fp_line
			(start -8.325 3.148)
			(end -1.397 3.148)
			(stroke
				(width 0.15)
				(type solid)
			)
			(layer "F.Fab")
		)
		(fp_text user "${REFERENCE}"
			(at -8.933 9.438 90)
			(layer "F.Fab")
			(effects
				(font
					(size 0.7 0.7)
					(thickness 0.15)
				)
				(justify left bottom)
			)
		)
		(fp_text user "Author: Antmicro"
			(at -8.933 8.237 90)
			(layer "F.Fab")
			(effects
				(font
					(size 0.7 0.7)
					(thickness 0.15)
				)
				(justify left bottom)
			)
		)
		(fp_text user "License: Apache-2.0"
			(at -8.933 7.038 90)
			(layer "F.Fab")
			(effects
				(font
					(size 0.7 0.7)
					(thickness 0.15)
				)
				(justify left bottom)
			)
		)
		(pad "1" smd rect
			(at -6 2.128 90)
			(size 1 2.75)
			(layers "F.Cu" "F.Mask" "F.Paste")
			(net 1 "GND")
			(pintype "passive")
		)
		(pad "2" smd rect
			(at -6 -2.13 90)
			(size 1 2.75)
			(layers "F.Cu" "F.Mask" "F.Paste")
			(net 797 "+1V8")
			(pintype "passive")
		)
		(pad "3" smd rect
			(at -4 2.128 90)
			(size 1 2.75)
			(layers "F.Cu" "F.Mask" "F.Paste")
			(net 1 "GND")
			(pintype "passive")
		)
		(pad "4" smd rect
			(at -4 -2.13 90)
			(size 1 2.75)
			(layers "F.Cu" "F.Mask" "F.Paste")
			(net 238 "/Debug FTDI + VNA/JTAG.TMS")
			(pintype "passive")
		)
		(pad "5" smd rect
			(at -2 2.128 90)
			(size 1 2.75)
			(layers "F.Cu" "F.Mask" "F.Paste")
			(net 1 "GND")
			(pintype "passive")
		)
		(pad "6" smd rect
			(at -2 -2.13 90)
			(size 1 2.75)
			(layers "F.Cu" "F.Mask" "F.Paste")
			(net 239 "/Debug FTDI + VNA/JTAG.TCK")
			(pintype "passive")
		)
		(pad "7" smd rect
			(at 0 2.128 90)
			(size 1 2.75)
			(layers "F.Cu" "F.Mask" "F.Paste")
			(net 1 "GND")
			(pintype "passive")
		)
		(pad "8" smd rect
			(at 0 -2.13 90)
			(size 1 2.75)
			(layers "F.Cu" "F.Mask" "F.Paste")
			(net 242 "/Debug FTDI + VNA/JTAG.TDO")
			(pintype "passive")
		)
		(pad "9" smd rect
			(at 1.999 2.128 90)
			(size 1 2.75)
			(layers "F.Cu" "F.Mask" "F.Paste")
			(net 1 "GND")
			(pintype "passive")
		)
		(pad "10" smd rect
			(at 1.999 -2.13 90)
			(size 1 2.75)
			(layers "F.Cu" "F.Mask" "F.Paste")
			(net 244 "/Debug FTDI + VNA/JTAG.TDI")
			(pintype "passive")
		)
		(pad "11" smd rect
			(at 3.999 2.128 90)
			(size 1 2.75)
			(layers "F.Cu" "F.Mask" "F.Paste")
			(net 1 "GND")
			(pintype "passive")
		)
		(pad "12" smd rect
			(at 3.999 -2.13 90)
			(size 1 2.75)
			(layers "F.Cu" "F.Mask" "F.Paste")
			(net 240 "unconnected-(J1-Pad12)")
			(pintype "passive+no_connect")
		)
		(pad "13" smd rect
			(at 5.998 2.128 90)
			(size 1 2.75)
			(layers "F.Cu" "F.Mask" "F.Paste")
			(net 1 "GND")
			(pintype "passive")
		)
		(pad "14" smd rect
			(at 5.998 -2.13 90)
			(size 1 2.75)
			(layers "F.Cu" "F.Mask" "F.Paste")
			(net 241 "unconnected-(J1-Pad14)")
			(pintype "passive+no_connect")
		)
	)
	(footprint "antmicro-footprints:BarrelJack_Pin2mm_694106106102"
		(layer "F.Cu")
		(at 259.67 119.47)
		(property "Reference" "J7"
			(at -7.17 -4.97 0)
			(layer "F.SilkS")
			(effects
				(font
					(size 0.7 0.7)
					(thickness 0.15)
				)
				(justify left bottom)
			)
		)
		(property "Value" "BarrelJack_Pin2mm_694106106102"
			(at -8.13 7.78 0)
			(layer "F.Fab")
			(effects
				(font
					(size 0.7 0.7)
					(thickness 0.15)
				)
				(justify left bottom)
			)
		)
		(property "Datasheet" "https://www.we-online.com/components/products/datasheet/694106106102.pdf"
			(at 2.55 0 0)
			(layer "F.Fab")
			(hide yes)
			(effects
				(font
					(size 0.7 0.7)
					(thickness 0.15)
				)
				(justify left bottom)
			)
		)
		(property "Description" "DC Power Connector, Jack, 5 A, 2 mm, PCB Mount, Surface Mount"
			(at 2.55 0 0)
			(layer "F.Fab")
			(hide yes)
			(effects
				(font
					(size 0.7 0.7)
					(thickness 0.15)
				)
				(justify left bottom)
			)
		)
		(property "MPN" "694106106102"
			(at 0 0 0)
			(unlocked yes)
			(layer "F.Fab")
			(hide yes)
			(effects
				(font
					(size 1 1)
					(thickness 0.15)
				)
			)
		)
		(property "Manufacturer" "Würth Elektronik"
			(at 0 0 0)
			(unlocked yes)
			(layer "F.Fab")
			(hide yes)
			(effects
				(font
					(size 1 1)
					(thickness 0.15)
				)
			)
		)
		(property "Author" "Antmicro"
			(at 0 0 0)
			(unlocked yes)
			(layer "F.Fab")
			(hide yes)
			(effects
				(font
					(size 1 1)
					(thickness 0.15)
				)
			)
		)
		(property "License" "Apache-2.0"
			(at 0 0 0)
			(unlocked yes)
			(layer "F.Fab")
			(hide yes)
			(effects
				(font
					(size 1 1)
					(thickness 0.15)
				)
			)
		)
		(sheetname "/Supply/")
		(sheetfile "supply.kicad_sch")
		(attr smd)
		(fp_line
			(start -7.3 -4.49)
			(end -7.3 -2.59)
			(stroke
				(width 0.15)
				(type solid)
			)
			(layer "F.SilkS")
		)
		(fp_line
			(start -7.3 -4.49)
			(end -5.1 -4.49)
			(stroke
				(width 0.15)
				(type solid)
			)
			(layer "F.SilkS")
		)
		(fp_line
			(start -6.54 4.98)
			(end -6.54 3.67)
			(stroke
				(width 0.15)
				(type solid)
			)
			(layer "F.SilkS")
		)
		(fp_line
			(start -6.54 4.98)
			(end -5.23 4.98)
			(stroke
				(width 0.15)
				(type solid)
			)
			(layer "F.SilkS")
		)
		(fp_line
			(start 0 -4.49)
			(end -1.9 -4.49)
			(stroke
				(width 0.15)
				(type solid)
			)
			(layer "F.SilkS")
		)
		(fp_line
			(start 0 4.9)
			(end -1.9 4.9)
			(stroke
				(width 0.15)
				(type solid)
			)
			(layer "F.SilkS")
		)
		(fp_line
			(start 3.905 -4.49)
			(end 3.915 4.51)
			(stroke
				(width 0.15)
				(type solid)
			)
			(layer "F.SilkS")
		)
		(fp_circle
			(center -8.05 5.4)
			(end -8 5.4)
			(stroke
				(width 0.15)
				(type solid)
			)
			(fill yes)
			(layer "F.SilkS")
		)
		(fp_rect
			(start -7.75 -6.8)
			(end 7.75 6.8)
			(stroke
				(width 0.05)
				(type solid)
			)
			(fill no)
			(layer "F.CrtYd")
		)
		(fp_rect
			(start -7.3 4.51)
			(end 7.4 -4.49)
			(stroke
				(width 0.15)
				(type solid)
			)
			(fill no)
			(layer "F.Fab")
		)
		(fp_rect
			(start 3.9 -4.49)
			(end 7.4 4.51)
			(stroke
				(width 0.15)
				(type solid)
			)
			(fill no)
			(layer "F.Fab")
		)
		(fp_text user "License: Apache-2.0"
			(at -8.1 8.8 0)
			(layer "F.Fab")
			(effects
				(font
					(size 0.7 0.7)
					(thickness 0.15)
				)
				(justify left bottom)
			)
		)
		(fp_text user "Author: Antmicro"
			(at -8.1 11.2 0)
			(layer "F.Fab")
			(effects
				(font
					(size 0.7 0.7)
					(thickness 0.15)
				)
				(justify left bottom)
			)
		)
		(fp_text user "${REFERENCE}"
			(at -8.1 10 0)
			(layer "F.Fab")
			(effects
				(font
					(size 0.7 0.7)
					(thickness 0.15)
				)
				(justify left bottom)
			)
		)
		(pad "" np_thru_hole circle
			(at -2.1 0 90)
			(size 1.8 1.8)
			(drill 1.8)
			(layers "*.Cu" "*.Mask")
		)
		(pad "" np_thru_hole circle
			(at 2.4 0 90)
			(size 1.6 1.6)
			(drill 1.6)
			(layers "*.Cu" "*.Mask")
		)
		(pad "1" smd roundrect
			(at -3.75 5.4 270)
			(size 2 2)
			(layers "F.Cu" "F.Mask" "F.Paste")
			(roundrect_rratio 0.1)
			(net 325 "/Supply/12V_aux")
			(pinfunction "1")
			(pintype "passive")
		)
		(pad "1" smd roundrect
			(at 2.4 5.4 270)
			(size 2 2)
			(layers "F.Cu" "F.Mask" "F.Paste")
			(roundrect_rratio 0.1)
			(net 325 "/Supply/12V_aux")
			(pinfunction "1")
			(pintype "passive")
		)
		(pad "2" smd roundrect
			(at 2.4 -5.4 270)
			(size 2 2)
			(layers "F.Cu" "F.Mask" "F.Paste")
			(roundrect_rratio 0.1)
			(net 1 "GND")
			(pinfunction "2")
			(pintype "passive")
		)
		(pad "3" smd roundrect
			(at -3.75 -5.4 270)
			(size 2 2)
			(layers "F.Cu" "F.Mask" "F.Paste")
			(roundrect_rratio 0.1)
			(net 1 "GND")
			(pinfunction "3")
			(pintype "passive")
		)
	)
)
